(kicad_pcb
	(version 20260206)
	(generator "pcbnew")
	(generator_version "10.0")
	(general
		(thickness 1.6)
		(legacy_teardrops no)
	)
	(paper "A4")
	(title_block
		(title "01162023_DA0F0TEBIF0_F0T_Expander_BD_F_brd_V02_OCP.brd")
		(comment 1 "Grand Teton / footprint 5622 of 9728 (PEX2), pads 1075-1189 of 2397")
	)
	(layers
		(0 "F.Cu" signal "TOP")
		(4 "In1.Cu" signal "GND")
		(6 "In2.Cu" signal "VCC")
		(8 "In3.Cu" signal "VCC1")
		(10 "In4.Cu" signal "GND1")
		(12 "In5.Cu" signal "IN1")
		(14 "In6.Cu" signal "GND2")
		(16 "In7.Cu" signal "IN2")
		(18 "In8.Cu" signal "GND3")
		(20 "In9.Cu" signal "IN3")
		(22 "In10.Cu" signal "GND4")
		(24 "In11.Cu" signal "IN4")
		(26 "In12.Cu" signal "GND5")
		(28 "In13.Cu" signal "IN5")
		(30 "In14.Cu" signal "GND6")
		(32 "In15.Cu" signal "IN6")
		(34 "In16.Cu" signal "GND7")
		(2 "B.Cu" signal "BOTTOM")
		(9 "F.Adhes" user "F.Adhesive")
		(11 "B.Adhes" user "B.Adhesive")
		(13 "F.Paste" user "Package Geometry/Pastemask Top")
		(15 "B.Paste" user "Package Geometry/Pastemask Bottom")
		(5 "F.SilkS" user "Ref Des/Silkscreen Top")
		(7 "B.SilkS" user "Ref Des/Silkscreen Bottom")
		(1 "F.Mask" user "Board Geometry/Soldermask Top")
		(3 "B.Mask" user "Board Geometry/Soldermask Bottom")
		(17 "Dwgs.User" user "User.Drawings")
		(19 "Cmts.User" user "User.Comments")
		(21 "Eco1.User" user "User.Eco1")
		(23 "Eco2.User" user "User.Eco2")
		(25 "Edge.Cuts" user "Board Geometry/Outline")
		(27 "Margin" user)
		(31 "F.CrtYd" user "Package Geometry/Place Bound Top")
		(29 "B.CrtYd" user "Package Geometry/Place Bound Bottom")
		(35 "F.Fab" user "Ref Des/Assembly Top")
		(33 "B.Fab" user "Ref Des/Assembly Bottom")
	)
	(footprint ""
		(layer "F.Cu")
		(at 291.84981 -295.89984)
		(property "Reference" "PEX2"
			(at -3.35153 35.56762 0)
			(unlocked yes)
			(layer "F.SilkS")
			(effects
				(font
					(size 2.032 1.524)
					(thickness 0.1524)
				)
				(justify left)
			)
		)
		(property "Value" ""
			(at 0 0 0)
			(layer "F.Fab")
			(effects
				(font
					(size 1.27 1.27)
				)
			)
		)
		(duplicate_pad_numbers_are_jumpers no)
		(pad "B48" smd circle
			(at 21.850096 -21.850096)
			(size 0.4572 0.4572)
			(layers "F.Cu" "F.Mask" "F.Paste")
			(net "GND")
		)
		(pad "B49" smd circle
			(at 22.800056 -21.850096)
			(size 0.4572 0.4572)
			(layers "F.Cu" "F.Mask" "F.Paste")
			(net "GND")
		)
		(pad "BA1" smd circle
			(at -22.800056 15.200122)
			(size 0.4572 0.4572)
			(layers "F.Cu" "F.Mask" "F.Paste")
			(net "GND")
		)
		(pad "BA2" smd circle
			(at -21.850096 15.200122)
			(size 0.4572 0.4572)
			(layers "F.Cu" "F.Mask" "F.Paste")
			(net "GND")
		)
		(pad "BA3" smd circle
			(at -20.899882 15.200122)
			(size 0.4572 0.4572)
			(layers "F.Cu" "F.Mask" "F.Paste")
			(net "GND")
		)
		(pad "BA4" smd circle
			(at -19.949922 15.200122)
			(size 0.4572 0.4572)
			(layers "F.Cu" "F.Mask" "F.Paste")
			(net "Net_1416")
		)
		(pad "BA5" smd circle
			(at -18.999962 15.200122)
			(size 0.4572 0.4572)
			(layers "F.Cu" "F.Mask" "F.Paste")
			(net "GND")
		)
		(pad "BA6" smd circle
			(at -18.050002 15.200122)
			(size 0.4572 0.4572)
			(layers "F.Cu" "F.Mask" "F.Paste")
			(net "Net_1736")
		)
		(pad "BA7" smd circle
			(at -17.100042 15.200122)
			(size 0.4572 0.4572)
			(layers "F.Cu" "F.Mask" "F.Paste")
			(net "GND")
		)
		(pad "BA8" smd circle
			(at -16.150082 15.200122)
			(size 0.4572 0.4572)
			(layers "F.Cu" "F.Mask" "F.Paste")
			(net "Net_1359")
		)
		(pad "BA9" smd circle
			(at -15.200122 15.200122)
			(size 0.4572 0.4572)
			(layers "F.Cu" "F.Mask" "F.Paste")
			(net "GND")
		)
		(pad "BA10" smd circle
			(at -14.249908 15.200122)
			(size 0.4572 0.4572)
			(layers "F.Cu" "F.Mask" "F.Paste")
			(net "P5E_PEX2_STN2_TX_DP<46>")
		)
		(pad "BA11" smd circle
			(at -13.299948 15.200122)
			(size 0.4572 0.4572)
			(layers "F.Cu" "F.Mask" "F.Paste")
			(net "GND")
		)
		(pad "BA12" smd circle
			(at -12.349988 15.200122)
			(size 0.4572 0.4572)
			(layers "F.Cu" "F.Mask" "F.Paste")
			(net "P5E_PEX2_STN2_TX_DP<44>")
		)
		(pad "BA13" smd circle
			(at -11.400028 15.200122)
			(size 0.4572 0.4572)
			(layers "F.Cu" "F.Mask" "F.Paste")
			(net "GND")
		)
		(pad "BA14" smd circle
			(at -10.450068 15.200122)
			(size 0.4572 0.4572)
			(layers "F.Cu" "F.Mask" "F.Paste")
			(net "P5E_PEX2_STN2_TX_DP<42>")
		)
		(pad "BA15" smd circle
			(at -9.500108 15.200122)
			(size 0.4572 0.4572)
			(layers "F.Cu" "F.Mask" "F.Paste")
			(net "GND")
		)
		(pad "BA16" smd circle
			(at -8.549894 15.200122)
			(size 0.4572 0.4572)
			(layers "F.Cu" "F.Mask" "F.Paste")
			(net "P5E_PEX2_STN2_TX_DP<40>")
		)
		(pad "BA17" smd circle
			(at -7.599934 15.200122)
			(size 0.4572 0.4572)
			(layers "F.Cu" "F.Mask" "F.Paste")
			(net "GND")
		)
		(pad "BA18" smd circle
			(at -6.649974 15.200122)
			(size 0.4572 0.4572)
			(layers "F.Cu" "F.Mask" "F.Paste")
			(net "P5E_PEX2_STN2_TX_DP<38>")
		)
		(pad "BA19" smd circle
			(at -5.700014 15.200122)
			(size 0.4572 0.4572)
			(layers "F.Cu" "F.Mask" "F.Paste")
			(net "GND")
		)
		(pad "BA20" smd circle
			(at -4.750054 15.200122)
			(size 0.4572 0.4572)
			(layers "F.Cu" "F.Mask" "F.Paste")
			(net "P5E_PEX2_STN2_TX_DP<36>")
		)
		(pad "BA21" smd circle
			(at -3.800094 15.200122)
			(size 0.4572 0.4572)
			(layers "F.Cu" "F.Mask" "F.Paste")
			(net "GND")
		)
		(pad "BA22" smd circle
			(at -2.84988 15.200122)
			(size 0.4572 0.4572)
			(layers "F.Cu" "F.Mask" "F.Paste")
			(net "P5E_PEX2_STN2_TX_DP<34>")
		)
		(pad "BA23" smd circle
			(at -1.89992 15.200122)
			(size 0.4572 0.4572)
			(layers "F.Cu" "F.Mask" "F.Paste")
			(net "GND")
		)
		(pad "BA24" smd circle
			(at -0.94996 15.200122)
			(size 0.4572 0.4572)
			(layers "F.Cu" "F.Mask" "F.Paste")
			(net "P5E_PEX2_STN2_TX_DP<32>")
		)
		(pad "BA25" smd circle
			(at 0 15.200122)
			(size 0.4572 0.4572)
			(layers "F.Cu" "F.Mask" "F.Paste")
			(net "GND")
		)
		(pad "BA26" smd circle
			(at 0.94996 15.200122)
			(size 0.4572 0.4572)
			(layers "F.Cu" "F.Mask" "F.Paste")
			(net "P5E_PEX2_STN1_TX_DN<17>")
		)
		(pad "BA27" smd circle
			(at 1.89992 15.200122)
			(size 0.4572 0.4572)
			(layers "F.Cu" "F.Mask" "F.Paste")
			(net "GND")
		)
		(pad "BA28" smd circle
			(at 2.84988 15.200122)
			(size 0.4572 0.4572)
			(layers "F.Cu" "F.Mask" "F.Paste")
			(net "P5E_PEX2_STN1_TX_DN<19>")
		)
		(pad "BA29" smd circle
			(at 3.800094 15.200122)
			(size 0.4572 0.4572)
			(layers "F.Cu" "F.Mask" "F.Paste")
			(net "GND")
		)
		(pad "BA30" smd circle
			(at 4.750054 15.200122)
			(size 0.4572 0.4572)
			(layers "F.Cu" "F.Mask" "F.Paste")
			(net "P5E_PEX2_STN1_TX_DN<21>")
		)
		(pad "BA31" smd circle
			(at 5.700014 15.200122)
			(size 0.4572 0.4572)
			(layers "F.Cu" "F.Mask" "F.Paste")
			(net "GND")
		)
		(pad "BA32" smd circle
			(at 6.649974 15.200122)
			(size 0.4572 0.4572)
			(layers "F.Cu" "F.Mask" "F.Paste")
			(net "P5E_PEX2_STN1_TX_DN<23>")
		)
		(pad "BA33" smd circle
			(at 7.599934 15.200122)
			(size 0.4572 0.4572)
			(layers "F.Cu" "F.Mask" "F.Paste")
			(net "GND")
		)
		(pad "BA34" smd circle
			(at 8.549894 15.200122)
			(size 0.4572 0.4572)
			(layers "F.Cu" "F.Mask" "F.Paste")
			(net "P5E_PEX2_STN1_TX_DN<25>")
		)
		(pad "BA35" smd circle
			(at 9.500108 15.200122)
			(size 0.4572 0.4572)
			(layers "F.Cu" "F.Mask" "F.Paste")
			(net "GND")
		)
		(pad "BA36" smd circle
			(at 10.450068 15.200122)
			(size 0.4572 0.4572)
			(layers "F.Cu" "F.Mask" "F.Paste")
			(net "P5E_PEX2_STN1_TX_DN<27>")
		)
		(pad "BA37" smd circle
			(at 11.400028 15.200122)
			(size 0.4572 0.4572)
			(layers "F.Cu" "F.Mask" "F.Paste")
			(net "GND")
		)
		(pad "BA38" smd circle
			(at 12.349988 15.200122)
			(size 0.4572 0.4572)
			(layers "F.Cu" "F.Mask" "F.Paste")
			(net "P5E_PEX2_STN1_TX_DN<29>")
		)
		(pad "BA39" smd circle
			(at 13.299948 15.200122)
			(size 0.4572 0.4572)
			(layers "F.Cu" "F.Mask" "F.Paste")
			(net "GND")
		)
		(pad "BA40" smd circle
			(at 14.249908 15.200122)
			(size 0.4572 0.4572)
			(layers "F.Cu" "F.Mask" "F.Paste")
			(net "P5E_PEX2_STN1_TX_DN<31>")
		)
		(pad "BA41" smd circle
			(at 15.200122 15.200122)
			(size 0.4572 0.4572)
			(layers "F.Cu" "F.Mask" "F.Paste")
			(net "GND")
		)
		(pad "BA42" smd circle
			(at 16.150082 15.200122)
			(size 0.4572 0.4572)
			(layers "F.Cu" "F.Mask" "F.Paste")
			(net "P5E_PEX2_STN0_TX_DN<14>")
		)
		(pad "BA43" smd circle
			(at 17.100042 15.200122)
			(size 0.4572 0.4572)
			(layers "F.Cu" "F.Mask" "F.Paste")
			(net "GND")
		)
		(pad "BA44" smd circle
			(at 18.050002 15.200122)
			(size 0.4572 0.4572)
			(layers "F.Cu" "F.Mask" "F.Paste")
			(net "P5E_PEX2_STN0_TX_DN<12>")
		)
		(pad "BA45" smd circle
			(at 18.999962 15.200122)
			(size 0.4572 0.4572)
			(layers "F.Cu" "F.Mask" "F.Paste")
			(net "GND")
		)
		(pad "BA46" smd circle
			(at 19.949922 15.200122)
			(size 0.4572 0.4572)
			(layers "F.Cu" "F.Mask" "F.Paste")
			(net "P5E_PEX2_STN0_TX_DP<10>")
		)
		(pad "BA47" smd circle
			(at 20.899882 15.200122)
			(size 0.4572 0.4572)
			(layers "F.Cu" "F.Mask" "F.Paste")
			(net "GND")
		)
		(pad "BA48" smd circle
			(at 21.850096 15.200122)
			(size 0.4572 0.4572)
			(layers "F.Cu" "F.Mask" "F.Paste")
			(net "GND")
		)
		(pad "BA49" smd circle
			(at 22.800056 15.200122)
			(size 0.4572 0.4572)
			(layers "F.Cu" "F.Mask" "F.Paste")
			(net "GND")
		)
		(pad "BB1" smd circle
			(at -22.800056 16.150082)
			(size 0.4572 0.4572)
			(layers "F.Cu" "F.Mask" "F.Paste")
			(net "Net_1439")
		)
		(pad "BB2" smd circle
			(at -21.850096 16.150082)
			(size 0.4572 0.4572)
			(layers "F.Cu" "F.Mask" "F.Paste")
			(net "Net_1387")
		)
		(pad "BB3" smd circle
			(at -20.899882 16.150082)
			(size 0.4572 0.4572)
			(layers "F.Cu" "F.Mask" "F.Paste")
			(net "GND")
		)
		(pad "BB4" smd circle
			(at -19.949922 16.150082)
			(size 0.4572 0.4572)
			(layers "F.Cu" "F.Mask" "F.Paste")
			(net "Net_1733")
		)
		(pad "BB5" smd circle
			(at -18.999962 16.150082)
			(size 0.4572 0.4572)
			(layers "F.Cu" "F.Mask" "F.Paste")
			(net "GND")
		)
		(pad "BB6" smd circle
			(at -18.050002 16.150082)
			(size 0.4572 0.4572)
			(layers "F.Cu" "F.Mask" "F.Paste")
			(net "Net_1391")
		)
		(pad "BB7" smd circle
			(at -17.100042 16.150082)
			(size 0.4572 0.4572)
			(layers "F.Cu" "F.Mask" "F.Paste")
			(net "GND")
		)
		(pad "BB8" smd circle
			(at -16.150082 16.150082)
			(size 0.4572 0.4572)
			(layers "F.Cu" "F.Mask" "F.Paste")
			(net "Net_1726")
		)
		(pad "BB9" smd circle
			(at -15.200122 16.150082)
			(size 0.4572 0.4572)
			(layers "F.Cu" "F.Mask" "F.Paste")
			(net "GND")
		)
		(pad "BB10" smd circle
			(at -14.249908 16.150082)
			(size 0.4572 0.4572)
			(layers "F.Cu" "F.Mask" "F.Paste")
			(net "P5E_PEX2_STN2_TX_DN<46>")
		)
		(pad "BB11" smd circle
			(at -13.299948 16.150082)
			(size 0.4572 0.4572)
			(layers "F.Cu" "F.Mask" "F.Paste")
			(net "GND")
		)
		(pad "BB12" smd circle
			(at -12.349988 16.150082)
			(size 0.4572 0.4572)
			(layers "F.Cu" "F.Mask" "F.Paste")
			(net "P5E_PEX2_STN2_TX_DN<44>")
		)
		(pad "BB13" smd circle
			(at -11.400028 16.150082)
			(size 0.4572 0.4572)
			(layers "F.Cu" "F.Mask" "F.Paste")
			(net "GND")
		)
		(pad "BB14" smd circle
			(at -10.450068 16.150082)
			(size 0.4572 0.4572)
			(layers "F.Cu" "F.Mask" "F.Paste")
			(net "P5E_PEX2_STN2_TX_DN<42>")
		)
		(pad "BB15" smd circle
			(at -9.500108 16.150082)
			(size 0.4572 0.4572)
			(layers "F.Cu" "F.Mask" "F.Paste")
			(net "GND")
		)
		(pad "BB16" smd circle
			(at -8.549894 16.150082)
			(size 0.4572 0.4572)
			(layers "F.Cu" "F.Mask" "F.Paste")
			(net "P5E_PEX2_STN2_TX_DN<40>")
		)
		(pad "BB17" smd circle
			(at -7.599934 16.150082)
			(size 0.4572 0.4572)
			(layers "F.Cu" "F.Mask" "F.Paste")
			(net "GND")
		)
		(pad "BB18" smd circle
			(at -6.649974 16.150082)
			(size 0.4572 0.4572)
			(layers "F.Cu" "F.Mask" "F.Paste")
			(net "P5E_PEX2_STN2_TX_DN<38>")
		)
		(pad "BB19" smd circle
			(at -5.700014 16.150082)
			(size 0.4572 0.4572)
			(layers "F.Cu" "F.Mask" "F.Paste")
			(net "GND")
		)
		(pad "BB20" smd circle
			(at -4.750054 16.150082)
			(size 0.4572 0.4572)
			(layers "F.Cu" "F.Mask" "F.Paste")
			(net "P5E_PEX2_STN2_TX_DN<36>")
		)
		(pad "BB21" smd circle
			(at -3.800094 16.150082)
			(size 0.4572 0.4572)
			(layers "F.Cu" "F.Mask" "F.Paste")
			(net "GND")
		)
		(pad "BB22" smd circle
			(at -2.84988 16.150082)
			(size 0.4572 0.4572)
			(layers "F.Cu" "F.Mask" "F.Paste")
			(net "P5E_PEX2_STN2_TX_DN<34>")
		)
		(pad "BB23" smd circle
			(at -1.89992 16.150082)
			(size 0.4572 0.4572)
			(layers "F.Cu" "F.Mask" "F.Paste")
			(net "GND")
		)
		(pad "BB24" smd circle
			(at -0.94996 16.150082)
			(size 0.4572 0.4572)
			(layers "F.Cu" "F.Mask" "F.Paste")
			(net "P5E_PEX2_STN2_TX_DN<32>")
		)
		(pad "BB25" smd circle
			(at 0 16.150082)
			(size 0.4572 0.4572)
			(layers "F.Cu" "F.Mask" "F.Paste")
			(net "GND")
		)
		(pad "BB26" smd circle
			(at 0.94996 16.150082)
			(size 0.4572 0.4572)
			(layers "F.Cu" "F.Mask" "F.Paste")
			(net "P5E_PEX2_STN1_TX_DP<17>")
		)
		(pad "BB27" smd circle
			(at 1.89992 16.150082)
			(size 0.4572 0.4572)
			(layers "F.Cu" "F.Mask" "F.Paste")
			(net "GND")
		)
		(pad "BB28" smd circle
			(at 2.84988 16.150082)
			(size 0.4572 0.4572)
			(layers "F.Cu" "F.Mask" "F.Paste")
			(net "P5E_PEX2_STN1_TX_DP<19>")
		)
		(pad "BB29" smd circle
			(at 3.800094 16.150082)
			(size 0.4572 0.4572)
			(layers "F.Cu" "F.Mask" "F.Paste")
			(net "GND")
		)
		(pad "BB30" smd circle
			(at 4.750054 16.150082)
			(size 0.4572 0.4572)
			(layers "F.Cu" "F.Mask" "F.Paste")
			(net "P5E_PEX2_STN1_TX_DP<21>")
		)
		(pad "BB31" smd circle
			(at 5.700014 16.150082)
			(size 0.4572 0.4572)
			(layers "F.Cu" "F.Mask" "F.Paste")
			(net "GND")
		)
		(pad "BB32" smd circle
			(at 6.649974 16.150082)
			(size 0.4572 0.4572)
			(layers "F.Cu" "F.Mask" "F.Paste")
			(net "P5E_PEX2_STN1_TX_DP<23>")
		)
		(pad "BB33" smd circle
			(at 7.599934 16.150082)
			(size 0.4572 0.4572)
			(layers "F.Cu" "F.Mask" "F.Paste")
			(net "GND")
		)
		(pad "BB34" smd circle
			(at 8.549894 16.150082)
			(size 0.4572 0.4572)
			(layers "F.Cu" "F.Mask" "F.Paste")
			(net "P5E_PEX2_STN1_TX_DP<25>")
		)
		(pad "BB35" smd circle
			(at 9.500108 16.150082)
			(size 0.4572 0.4572)
			(layers "F.Cu" "F.Mask" "F.Paste")
			(net "GND")
		)
		(pad "BB36" smd circle
			(at 10.450068 16.150082)
			(size 0.4572 0.4572)
			(layers "F.Cu" "F.Mask" "F.Paste")
			(net "P5E_PEX2_STN1_TX_DP<27>")
		)
		(pad "BB37" smd circle
			(at 11.400028 16.150082)
			(size 0.4572 0.4572)
			(layers "F.Cu" "F.Mask" "F.Paste")
			(net "GND")
		)
		(pad "BB38" smd circle
			(at 12.349988 16.150082)
			(size 0.4572 0.4572)
			(layers "F.Cu" "F.Mask" "F.Paste")
			(net "P5E_PEX2_STN1_TX_DP<29>")
		)
		(pad "BB39" smd circle
			(at 13.299948 16.150082)
			(size 0.4572 0.4572)
			(layers "F.Cu" "F.Mask" "F.Paste")
			(net "GND")
		)
		(pad "BB40" smd circle
			(at 14.249908 16.150082)
			(size 0.4572 0.4572)
			(layers "F.Cu" "F.Mask" "F.Paste")
			(net "P5E_PEX2_STN1_TX_DP<31>")
		)
		(pad "BB41" smd circle
			(at 15.200122 16.150082)
			(size 0.4572 0.4572)
			(layers "F.Cu" "F.Mask" "F.Paste")
			(net "GND")
		)
		(pad "BB42" smd circle
			(at 16.150082 16.150082)
			(size 0.4572 0.4572)
			(layers "F.Cu" "F.Mask" "F.Paste")
			(net "P5E_PEX2_STN0_TX_DP<14>")
		)
		(pad "BB43" smd circle
			(at 17.100042 16.150082)
			(size 0.4572 0.4572)
			(layers "F.Cu" "F.Mask" "F.Paste")
			(net "GND")
		)
		(pad "BB44" smd circle
			(at 18.050002 16.150082)
			(size 0.4572 0.4572)
			(layers "F.Cu" "F.Mask" "F.Paste")
			(net "P5E_PEX2_STN0_TX_DP<12>")
		)
		(pad "BB45" smd circle
			(at 18.999962 16.150082)
			(size 0.4572 0.4572)
			(layers "F.Cu" "F.Mask" "F.Paste")
			(net "GND")
		)
		(pad "BB46" smd circle
			(at 19.949922 16.150082)
			(size 0.4572 0.4572)
			(layers "F.Cu" "F.Mask" "F.Paste")
			(net "P5E_PEX2_STN0_TX_DN<10>")
		)
		(pad "BB47" smd circle
			(at 20.899882 16.150082)
			(size 0.4572 0.4572)
			(layers "F.Cu" "F.Mask" "F.Paste")
			(net "GND")
		)
		(pad "BB48" smd circle
			(at 21.850096 16.150082)
			(size 0.4572 0.4572)
			(layers "F.Cu" "F.Mask" "F.Paste")
			(net "P5E_PEX2_STN0_TX_DP<7>")
		)
		(pad "BB49" smd circle
			(at 22.800056 16.150082)
			(size 0.4572 0.4572)
			(layers "F.Cu" "F.Mask" "F.Paste")
			(net "P5E_PEX2_STN0_TX_DN<7>")
		)
		(pad "BC1" smd circle
			(at -22.800056 17.100042)
			(size 0.4572 0.4572)
			(layers "F.Cu" "F.Mask" "F.Paste")
			(net "GND")
		)
		(pad "BC2" smd circle
			(at -21.850096 17.100042)
			(size 0.4572 0.4572)
			(layers "F.Cu" "F.Mask" "F.Paste")
			(net "GND")
		)
		(pad "BC3" smd circle
			(at -20.899882 17.100042)
			(size 0.4572 0.4572)
			(layers "F.Cu" "F.Mask" "F.Paste")
			(net "Net_1402")
		)
		(pad "BC4" smd circle
			(at -19.949922 17.100042)
			(size 0.4572 0.4572)
			(layers "F.Cu" "F.Mask" "F.Paste")
			(net "GND")
		)
		(pad "BC5" smd circle
			(at -18.999962 17.100042)
			(size 0.4572 0.4572)
			(layers "F.Cu" "F.Mask" "F.Paste")
			(net "Net_1722")
		)
		(pad "BC6" smd circle
			(at -18.050002 17.100042)
			(size 0.4572 0.4572)
			(layers "F.Cu" "F.Mask" "F.Paste")
			(net "GND")
		)
		(pad "BC7" smd circle
			(at -17.100042 17.100042)
			(size 0.4572 0.4572)
			(layers "F.Cu" "F.Mask" "F.Paste")
			(net "Net_1735")
		)
		(pad "BC8" smd circle
			(at -16.150082 17.100042)
			(size 0.4572 0.4572)
			(layers "F.Cu" "F.Mask" "F.Paste")
			(net "GND")
		)
		(pad "BC9" smd circle
			(at -15.200122 17.100042)
			(size 0.4572 0.4572)
			(layers "F.Cu" "F.Mask" "F.Paste")
			(net "P5E_PEX2_STN2_TX_DP<47>")
		)
		(pad "BC10" smd circle
			(at -14.249908 17.100042)
			(size 0.4572 0.4572)
			(layers "F.Cu" "F.Mask" "F.Paste")
			(net "GND")
		)
		(pad "BC11" smd circle
			(at -13.299948 17.100042)
			(size 0.4572 0.4572)
			(layers "F.Cu" "F.Mask" "F.Paste")
			(net "P5E_PEX2_STN2_TX_DP<45>")
		)
		(pad "BC12" smd circle
			(at -12.349988 17.100042)
			(size 0.4572 0.4572)
			(layers "F.Cu" "F.Mask" "F.Paste")
			(net "GND")
		)
		(pad "BC13" smd circle
			(at -11.400028 17.100042)
			(size 0.4572 0.4572)
			(layers "F.Cu" "F.Mask" "F.Paste")
			(net "P5E_PEX2_STN2_TX_DP<43>")
		)
		(pad "BC14" smd circle
			(at -10.450068 17.100042)
			(size 0.4572 0.4572)
			(layers "F.Cu" "F.Mask" "F.Paste")
			(net "GND")
		)
		(pad "BC15" smd circle
			(at -9.500108 17.100042)
			(size 0.4572 0.4572)
			(layers "F.Cu" "F.Mask" "F.Paste")
			(net "P5E_PEX2_STN2_TX_DP<41>")
		)
	)
)
